(kicad_pcb
	(version 20260206)
	(generator "pcbnew")
	(generator_version "10.0")
	(general
		(thickness 1.6)
		(legacy_teardrops no)
	)
	(paper "A4")
	(title_block
		(title "03242023_DA0F0TMBIJ0_F0T_Motherboard_J_brd_V01_OCP.brd")
		(comment 1 "Grand Teton / footprints 2145-2148 of 6105")
	)
	(layers
		(0 "F.Cu" signal "TOP")
		(4 "In1.Cu" signal "GND")
		(6 "In2.Cu" signal "IN1")
		(8 "In3.Cu" signal "GND1")
		(10 "In4.Cu" signal "IN2")
		(12 "In5.Cu" signal "GND2")
		(14 "In6.Cu" signal "IN3")
		(16 "In7.Cu" signal "GND3")
		(18 "In8.Cu" signal "VCC")
		(20 "In9.Cu" signal "VCC1")
		(22 "In10.Cu" signal "GND4")
		(24 "In11.Cu" signal "IN4")
		(26 "In12.Cu" signal "GND5")
		(28 "In13.Cu" signal "IN5")
		(30 "In14.Cu" signal "GND6")
		(32 "In15.Cu" signal "IN6")
		(34 "In16.Cu" signal "GND7")
		(2 "B.Cu" signal "BOTTOM")
		(9 "F.Adhes" user "F.Adhesive")
		(11 "B.Adhes" user "B.Adhesive")
		(13 "F.Paste" user "Package Geometry/Pastemask Top")
		(15 "B.Paste" user "Package Geometry/Pastemask Bottom")
		(5 "F.SilkS" user "Ref Des/Silkscreen Top")
		(7 "B.SilkS" user "Ref Des/Silkscreen Bottom")
		(1 "F.Mask" user "Board Geometry/Soldermask Top")
		(3 "B.Mask" user "Board Geometry/Soldermask Bottom")
		(17 "Dwgs.User" user "User.Drawings")
		(19 "Cmts.User" user "User.Comments")
		(21 "Eco1.User" user "User.Eco1")
		(23 "Eco2.User" user "User.Eco2")
		(25 "Edge.Cuts" user "Board Geometry/Outline")
		(27 "Margin" user)
		(31 "F.CrtYd" user "Package Geometry/Place Bound Top")
		(29 "B.CrtYd" user "Package Geometry/Place Bound Bottom")
		(35 "F.Fab" user "Ref Des/Assembly Top")
		(33 "B.Fab" user "Ref Des/Assembly Bottom")
	)
	(footprint ""
		(layer "F.Cu")
		(at 448.418966 -73.02754)
		(property "Reference" "PU9"
			(at -8.757666 -1.038098 0)
			(unlocked yes)
			(layer "F.SilkS")
			(effects
				(font
					(size 0.7874 0.5842)
					(thickness 0.1524)
				)
				(justify left)
			)
		)
		(property "Value" ""
			(at 0 0 0)
			(layer "F.Fab")
			(effects
				(font
					(size 1.27 1.27)
				)
			)
		)
		(duplicate_pad_numbers_are_jumpers no)
		(fp_line
			(start -2.549906 -3.050032)
			(end -2.549906 -2.51968)
			(stroke
				(width 0.1524)
				(type default)
			)
			(layer "F.SilkS")
		)
		(fp_line
			(start -2.549906 2.4892)
			(end -2.549906 3.050032)
			(stroke
				(width 0.1524)
				(type default)
			)
			(layer "F.SilkS")
		)
		(fp_line
			(start -2.549906 3.050032)
			(end -1.9812 3.050032)
			(stroke
				(width 0.1524)
				(type default)
			)
			(layer "F.SilkS")
		)
		(fp_line
			(start -2.032 -3.050032)
			(end -2.549906 -3.050032)
			(stroke
				(width 0.1524)
				(type default)
			)
			(layer "F.SilkS")
		)
		(fp_line
			(start 1.9812 3.050032)
			(end 2.549906 3.050032)
			(stroke
				(width 0.1524)
				(type default)
			)
			(layer "F.SilkS")
		)
		(fp_line
			(start 2.549906 -3.050032)
			(end 2.032 -3.050032)
			(stroke
				(width 0.1524)
				(type default)
			)
			(layer "F.SilkS")
		)
		(fp_line
			(start 2.549906 -2.51968)
			(end 2.549906 -3.050032)
			(stroke
				(width 0.1524)
				(type default)
			)
			(layer "F.SilkS")
		)
		(fp_line
			(start 2.549906 3.050032)
			(end 2.549906 2.4892)
			(stroke
				(width 0.1524)
				(type default)
			)
			(layer "F.SilkS")
		)
		(fp_poly
			(pts
				(xy -3.111246 -2.409444) (xy -2.790444 -2.24917) (xy -3.111246 -2.088896)
			)
			(stroke
				(width 0)
				(type default)
			)
			(fill yes)
			(layer "F.SilkS")
		)
		(fp_line
			(start -2.549906 -3.050032)
			(end -2.549906 3.050032)
			(stroke
				(width 0.1)
				(type default)
			)
			(layer "F.Fab")
		)
		(fp_line
			(start -2.549906 3.050032)
			(end 2.549906 3.050032)
			(stroke
				(width 0.1)
				(type default)
			)
			(layer "F.Fab")
		)
		(fp_line
			(start 2.549906 -3.050032)
			(end -2.549906 -3.050032)
			(stroke
				(width 0.1)
				(type default)
			)
			(layer "F.Fab")
		)
		(fp_line
			(start 2.549906 3.050032)
			(end 2.549906 -3.050032)
			(stroke
				(width 0.1)
				(type default)
			)
			(layer "F.Fab")
		)
		(fp_poly
			(pts
				(xy -3.8354 -2.757932) (xy -3.8354 -1.741932) (xy -2.8194 -2.249932)
			)
			(stroke
				(width 0)
				(type default)
			)
			(fill yes)
			(layer "F.Fab")
		)
		(pad "1" smd rect
			(at -2.362708 -2.249932 90)
			(size 0.2794 0.5842)
			(layers "F.Cu" "F.Mask" "F.Paste")
			(net "P3V3_AUX_ILIM")
		)
		(pad "2" smd rect
			(at -2.350008 -1.75006 90)
			(size 0.2794 0.6096)
			(layers "F.Cu" "F.Mask" "F.Paste")
			(net "PWRGD_P3V3_AUX")
		)
		(pad "3" smd rect
			(at -2.350008 -1.249934 90)
			(size 0.2794 0.6096)
			(layers "F.Cu" "F.Mask" "F.Paste")
			(net "P12V_AUX")
		)
		(pad "4" smd rect
			(at -2.350008 -0.750062 90)
			(size 0.2794 0.6096)
			(layers "F.Cu" "F.Mask" "F.Paste")
			(net "P3V3_AUX_VCC")
		)
		(pad "5" smd rect
			(at -2.350008 -0.249936 90)
			(size 0.2794 0.6096)
			(layers "F.Cu" "F.Mask" "F.Paste")
			(net "P3V3_AUX_VDRV")
		)
		(pad "6" smd rect
			(at -2.350008 0.249936 90)
			(size 0.2794 0.6096)
			(layers "F.Cu" "F.Mask" "F.Paste")
			(net "NC_PU9_3")
		)
		(pad "7_10-19" smd circle
			(at 0 0.062484 270)
			(size 0 0)
			(layers "F.Cu" "F.Mask" "F.Paste")
			(net "GND")
		)
		(pad "11_18" smd circle
			(at 0 2.712466 270)
			(size 0 0)
			(layers "F.Cu" "F.Mask" "F.Paste")
			(net "SW_P3V3_AUX_SW")
		)
		(pad "20_24" smd circle
			(at 1.787906 0.749808)
			(size 0 0)
			(layers "F.Cu" "F.Mask" "F.Paste")
			(net "SW_P3V3_AUX_FLT")
		)
		(pad "25" smd rect
			(at 2.350008 -0.750062 90)
			(size 0.2794 0.6096)
			(layers "F.Cu" "F.Mask" "F.Paste")
			(net "SW_P3V3_AUX_BOOTR")
		)
		(pad "26" smd rect
			(at 2.350008 -1.249934 90)
			(size 0.2794 0.6096)
			(layers "F.Cu" "F.Mask" "F.Paste")
			(net "SW_P3V3_AUX_BOOT")
		)
		(pad "27" smd rect
			(at 2.350008 -1.75006 90)
			(size 0.2794 0.6096)
			(layers "F.Cu" "F.Mask" "F.Paste")
			(net "P3V3_AUX_EN")
		)
		(pad "28" smd rect
			(at 2.362708 -2.249932 90)
			(size 0.2794 0.5842)
			(layers "F.Cu" "F.Mask" "F.Paste")
			(net "P3V3_AUX_VOS")
		)
		(pad "29" smd rect
			(at 1.75006 -2.887726)
			(size 0.2794 0.5842)
			(layers "F.Cu" "F.Mask" "F.Paste")
			(net "P3V3_AUX_SS")
		)
		(pad "30" smd rect
			(at 1.249934 -2.875026)
			(size 0.2794 0.6096)
			(layers "F.Cu" "F.Mask" "F.Paste")
			(net "P3V3_AUX_FB")
		)
		(pad "31" smd rect
			(at 0.750062 -2.875026)
			(size 0.2794 0.6096)
			(layers "F.Cu" "F.Mask" "F.Paste")
			(net "GND")
		)
		(pad "32" smd rect
			(at 0.249936 -2.875026)
			(size 0.2794 0.6096)
			(layers "F.Cu" "F.Mask" "F.Paste")
			(net "GND")
		)
		(pad "33" smd rect
			(at -0.249936 -2.875026)
			(size 0.2794 0.6096)
			(layers "F.Cu" "F.Mask" "F.Paste")
			(net "NC_PU9_1")
		)
		(pad "34" smd rect
			(at -0.750062 -2.875026)
			(size 0.2794 0.6096)
			(layers "F.Cu" "F.Mask" "F.Paste")
			(net "NC_PU9_2")
		)
		(pad "35" smd rect
			(at -1.249934 -2.875026)
			(size 0.2794 0.6096)
			(layers "F.Cu" "F.Mask" "F.Paste")
			(net "NC_HICCUP")
		)
		(pad "36" smd rect
			(at -1.75006 -2.887726)
			(size 0.2794 0.5842)
			(layers "F.Cu" "F.Mask" "F.Paste")
			(net "P3V3_AUX_MODE")
		)
		(pad "37" smd rect
			(at -1.549908 0.150114 90)
			(size 0.3048 0.508)
			(layers "F.Cu" "F.Mask" "F.Paste")
			(net "NC_PU9_4")
		)
		(zone
			(layer "F.Cu")
			(hatch none 0.5)
			(connect_pads
				(clearance 0)
			)
			(min_thickness 0.25)
			(keepout
				(tracks not_allowed)
				(vias allowed)
				(pads allowed)
				(copperpour not_allowed)
				(footprints allowed)
			)
			(placement
				(enabled no)
				(sheetname "")
			)
			(fill
				(thermal_gap 0.5)
				(thermal_bridge_width 0.5)
				(island_removal_mode 0)
			)
			(polygon
				(pts
					(xy 446.148206 -70.627494) (xy 446.329308 -70.627494) (xy 446.36436 -70.662546) (xy 450.473572 -70.662546)
					(xy 450.508624 -70.627494) (xy 450.958966 -70.627494) (xy 450.958966 -70.452488) (xy 445.9732 -70.452488)
				)
			)
		)
		(zone
			(layer "F.Cu")
			(hatch none 0.5)
			(connect_pads
				(clearance 0)
			)
			(min_thickness 0.25)
			(keepout
				(tracks not_allowed)
				(vias allowed)
				(pads allowed)
				(copperpour not_allowed)
				(footprints allowed)
			)
			(placement
				(enabled no)
				(sheetname "")
			)
			(fill
				(thermal_gap 0.5)
				(thermal_bridge_width 0.5)
				(island_removal_mode 0)
			)
			(polygon
				(pts
					(xy 446.424558 -73.00087) (xy 446.564258 -73.00087) (xy 446.564258 -72.673972) (xy 447.173858 -72.673972)
					(xy 447.173858 -73.080626) (xy 446.564258 -73.080626) (xy 446.564258 -73.02627) (xy 446.424558 -73.02627)
					(xy 446.424558 -74.98334) (xy 446.399158 -74.98334) (xy 446.399158 -75.572366) (xy 446.971166 -75.572366)
					(xy 446.971166 -75.546966) (xy 449.866766 -75.546966) (xy 449.866766 -75.572366) (xy 450.438774 -75.572366)
					(xy 450.438774 -74.98334) (xy 450.413374 -74.98334) (xy 450.413374 -73.358502) (xy 449.344796 -73.358502)
					(xy 449.344796 -71.162418) (xy 450.473826 -71.162418) (xy 450.508624 -71.12762) (xy 450.958966 -71.12762)
					(xy 450.958966 -70.927468) (xy 450.529452 -70.927468) (xy 450.4944 -70.96252) (xy 449.044822 -70.96252)
					(xy 449.044822 -73.627488) (xy 450.193918 -73.627488) (xy 450.193918 -75.302618) (xy 446.644014 -75.302618)
					(xy 446.644014 -73.327514) (xy 447.394076 -73.327514) (xy 447.394076 -72.427592) (xy 446.424558 -72.427592)
				)
			)
		)
	)
	(footprint ""
		(layer "F.Cu")
		(at 151.56688 -44.351448)
		(property "Reference" "C1873"
			(at 0 0 0)
			(layer "F.SilkS")
			(hide yes)
			(effects
				(font
					(size 1.27 1.27)
				)
			)
		)
		(property "Value" ""
			(at 0 0 0)
			(layer "F.Fab")
			(effects
				(font
					(size 1.27 1.27)
				)
			)
		)
		(duplicate_pad_numbers_are_jumpers no)
		(fp_line
			(start -0.7874 -0.4064)
			(end 0.7874 -0.4064)
			(stroke
				(width 0.1524)
				(type default)
			)
			(layer "F.SilkS")
		)
		(fp_line
			(start -0.7874 0.4064)
			(end -0.7874 -0.4064)
			(stroke
				(width 0.1524)
				(type default)
			)
			(layer "F.SilkS")
		)
		(fp_line
			(start 0.7874 -0.4064)
			(end 0.7874 0.4064)
			(stroke
				(width 0.1524)
				(type default)
			)
			(layer "F.SilkS")
		)
		(fp_line
			(start 0.7874 0.4064)
			(end -0.7874 0.4064)
			(stroke
				(width 0.1524)
				(type default)
			)
			(layer "F.SilkS")
		)
		(fp_line
			(start -0.67945 -0.305054)
			(end -0.12065 -0.305054)
			(stroke
				(width 0.1)
				(type default)
			)
			(layer "F.Fab")
		)
		(fp_line
			(start -0.67945 0.3048)
			(end -0.67945 -0.305054)
			(stroke
				(width 0.1)
				(type default)
			)
			(layer "F.Fab")
		)
		(fp_line
			(start -0.12065 -0.305054)
			(end -0.12065 -0.2794)
			(stroke
				(width 0.1)
				(type default)
			)
			(layer "F.Fab")
		)
		(fp_line
			(start -0.12065 -0.2794)
			(end 0.12065 -0.2794)
			(stroke
				(width 0.1)
				(type default)
			)
			(layer "F.Fab")
		)
		(fp_line
			(start -0.12065 0.2794)
			(end -0.12065 0.3048)
			(stroke
				(width 0.1)
				(type default)
			)
			(layer "F.Fab")
		)
		(fp_line
			(start -0.12065 0.3048)
			(end -0.67945 0.3048)
			(stroke
				(width 0.1)
				(type default)
			)
			(layer "F.Fab")
		)
		(fp_line
			(start 0.120396 0.2794)
			(end -0.12065 0.2794)
			(stroke
				(width 0.1)
				(type default)
			)
			(layer "F.Fab")
		)
		(fp_line
			(start 0.120396 0.3048)
			(end 0.120396 0.2794)
			(stroke
				(width 0.1)
				(type default)
			)
			(layer "F.Fab")
		)
		(fp_line
			(start 0.12065 -0.3048)
			(end 0.67945 -0.3048)
			(stroke
				(width 0.1)
				(type default)
			)
			(layer "F.Fab")
		)
		(fp_line
			(start 0.12065 -0.2794)
			(end 0.12065 -0.3048)
			(stroke
				(width 0.1)
				(type default)
			)
			(layer "F.Fab")
		)
		(fp_line
			(start 0.67945 -0.3048)
			(end 0.67945 0.3048)
			(stroke
				(width 0.1)
				(type default)
			)
			(layer "F.Fab")
		)
		(fp_line
			(start 0.67945 0.3048)
			(end 0.120396 0.3048)
			(stroke
				(width 0.1)
				(type default)
			)
			(layer "F.Fab")
		)
		(pad "1" smd circle
			(at -0.40005 0)
			(size 0 0)
			(layers "F.Cu" "F.Mask" "F.Paste")
			(net "P3V3_AUX")
		)
		(pad "2" smd circle
			(at 0.40005 0)
			(size 0 0)
			(layers "F.Cu" "F.Mask" "F.Paste")
			(net "GND")
		)
	)
	(footprint ""
		(layer "F.Cu")
		(at 297.74642 -424.00601 90)
		(property "Reference" "Q129"
			(at -7.70382 9.049512 90)
			(unlocked yes)
			(layer "F.SilkS")
			(effects
				(font
					(size 0.7874 0.5842)
					(thickness 0.1524)
				)
				(justify left)
			)
		)
		(property "Value" ""
			(at 0 0 90)
			(layer "F.Fab")
			(effects
				(font
					(size 1.27 1.27)
				)
			)
		)
		(duplicate_pad_numbers_are_jumpers no)
		(fp_line
			(start 1.332738 -1.100074)
			(end 1.332738 1.100074)
			(stroke
				(width 0.1524)
				(type default)
			)
			(layer "F.SilkS")
		)
		(fp_line
			(start 0.4826 -1.100074)
			(end 1.332738 -1.100074)
			(stroke
				(width 0.1524)
				(type default)
			)
			(layer "F.SilkS")
		)
		(fp_line
			(start -0.4826 -1.100074)
			(end 0 -0.541274)
			(stroke
				(width 0.1524)
				(type default)
			)
			(layer "F.SilkS")
		)
		(fp_line
			(start -1.332738 -1.100074)
			(end -0.4826 -1.100074)
			(stroke
				(width 0.1524)
				(type default)
			)
			(layer "F.SilkS")
		)
		(fp_line
			(start 0 -0.541274)
			(end 0.4826 -1.100074)
			(stroke
				(width 0.1524)
				(type default)
			)
			(layer "F.SilkS")
		)
		(fp_line
			(start 1.332738 1.100074)
			(end -1.332738 1.100074)
			(stroke
				(width 0.1524)
				(type default)
			)
			(layer "F.SilkS")
		)
		(fp_line
			(start -1.332738 1.100074)
			(end -1.332738 -1.100074)
			(stroke
				(width 0.1524)
				(type default)
			)
			(layer "F.SilkS")
		)
		(fp_poly
			(pts
				(xy -2.25552 -1.425194) (xy -1.553464 -1.074166) (xy -2.25552 -0.723138)
			)
			(stroke
				(width 0)
				(type default)
			)
			(fill yes)
			(layer "F.SilkS")
		)
		(fp_line
			(start 0.674878 -1.100074)
			(end 0.674878 1.100074)
			(stroke
				(width 0.1)
				(type default)
			)
			(layer "F.Fab")
		)
		(fp_line
			(start -0.674878 -1.100074)
			(end 0.674878 -1.100074)
			(stroke
				(width 0.1)
				(type default)
			)
			(layer "F.Fab")
		)
		(fp_line
			(start 0.674878 1.100074)
			(end -0.674878 1.100074)
			(stroke
				(width 0.1)
				(type default)
			)
			(layer "F.Fab")
		)
		(fp_line
			(start -0.674878 1.100074)
			(end -0.674878 -1.100074)
			(stroke
				(width 0.1)
				(type default)
			)
			(layer "F.Fab")
		)
		(fp_poly
			(pts
				(xy -2.2352 -0.298958) (xy -2.2352 -1.001014) (xy -1.533144 -0.649986)
			)
			(stroke
				(width 0)
				(type default)
			)
			(fill yes)
			(layer "F.Fab")
		)
		(pad "1" smd rect
			(at -0.94996 -0.649986 180)
			(size 0.4318 0.508)
			(layers "F.Cu" "F.Mask" "F.Paste")
			(net "GND")
		)
		(pad "2" smd rect
			(at -0.94996 0 180)
			(size 0.4318 0.508)
			(layers "F.Cu" "F.Mask" "F.Paste")
			(net "GPU_3V3IO_RSVD5_FFU")
		)
		(pad "3" smd rect
			(at -0.94996 0.649986 180)
			(size 0.4318 0.508)
			(layers "F.Cu" "F.Mask" "F.Paste")
			(net "GPU_3V3IO_RSVD5_FFU_ISO")
		)
		(pad "4" smd rect
			(at 0.94996 0.649986 180)
			(size 0.4318 0.508)
			(layers "F.Cu" "F.Mask" "F.Paste")
			(net "GND")
		)
		(pad "5" smd rect
			(at 0.94996 0 180)
			(size 0.4318 0.508)
			(layers "F.Cu" "F.Mask" "F.Paste")
			(net "GPU_3V3IO_RSVD5_FFU_N")
		)
		(pad "6" smd rect
			(at 0.94996 -0.649986 180)
			(size 0.4318 0.508)
			(layers "F.Cu" "F.Mask" "F.Paste")
			(net "GPU_3V3IO_RSVD5_FFU_N")
		)
	)
	(footprint ""
		(layer "F.Cu")
		(at 106.399076 -79.078836)
		(property "Reference" "D92"
			(at -52.93741 38.649402 90)
			(unlocked yes)
			(layer "F.SilkS")
			(effects
				(font
					(size 0.635 0.4064)
					(thickness 0.1524)
				)
				(justify left)
			)
		)
		(property "Value" ""
			(at 0 0 0)
			(layer "F.Fab")
			(effects
				(font
					(size 1.27 1.27)
				)
			)
		)
		(duplicate_pad_numbers_are_jumpers no)
		(fp_line
			(start -0.90678 0.4826)
			(end -0.90678 -0.4699)
			(stroke
				(width 0.1524)
				(type default)
			)
			(layer "F.SilkS")
		)
		(fp_line
			(start -0.89408 -0.4826)
			(end 0.90678 -0.4826)
			(stroke
				(width 0.1524)
				(type default)
			)
			(layer "F.SilkS")
		)
		(fp_line
			(start -0.79248 -0.4826)
			(end 1.03378 -0.4826)
			(stroke
				(width 0.1524)
				(type default)
			)
			(layer "F.SilkS")
		)
		(fp_line
			(start -0.64008 -0.4826)
			(end 1.16078 -0.4826)
			(stroke
				(width 0.1524)
				(type default)
			)
			(layer "F.SilkS")
		)
		(fp_line
			(start 0.90678 -0.4826)
			(end 0.90678 0.4826)
			(stroke
				(width 0.1524)
				(type default)
			)
			(layer "F.SilkS")
		)
		(fp_line
			(start 0.90678 0.4826)
			(end -0.90678 0.4826)
			(stroke
				(width 0.1524)
				(type default)
			)
			(layer "F.SilkS")
		)
		(fp_line
			(start 1.03378 -0.4826)
			(end 1.03378 0.4826)
			(stroke
				(width 0.1524)
				(type default)
			)
			(layer "F.SilkS")
		)
		(fp_line
			(start 1.03378 0.4826)
			(end -0.79248 0.4826)
			(stroke
				(width 0.1524)
				(type default)
			)
			(layer "F.SilkS")
		)
		(fp_line
			(start 1.16078 -0.4826)
			(end 1.16078 0.4826)
			(stroke
				(width 0.1524)
				(type default)
			)
			(layer "F.SilkS")
		)
		(fp_line
			(start 1.16078 0.4826)
			(end -0.64008 0.4826)
			(stroke
				(width 0.1524)
				(type default)
			)
			(layer "F.SilkS")
		)
		(fp_line
			(start -0.499872 -0.249936)
			(end 0.499872 -0.249936)
			(stroke
				(width 0.1)
				(type default)
			)
			(layer "F.Fab")
		)
		(fp_line
			(start -0.499872 0.249936)
			(end -0.499872 -0.249936)
			(stroke
				(width 0.1)
				(type default)
			)
			(layer "F.Fab")
		)
		(fp_line
			(start 0.499872 -0.249936)
			(end 0.499872 0.249936)
			(stroke
				(width 0.1)
				(type default)
			)
			(layer "F.Fab")
		)
		(fp_line
			(start 0.499872 0.249936)
			(end -0.499872 0.249936)
			(stroke
				(width 0.1)
				(type default)
			)
			(layer "F.Fab")
		)
		(pad "A" smd rect
			(at -0.47498 0)
			(size 0.6096 0.7112)
			(layers "F.Cu" "F.Mask" "F.Paste")
			(net "LED_PWRGD_P1V05_PCH_AUX")
		)
		(pad "C" smd rect
			(at 0.47498 0)
			(size 0.6096 0.7112)
			(layers "F.Cu" "F.Mask" "F.Paste")
			(net "LED_PWRGD_P1V05_PCH_AUX_D")
		)
	)
)
